(kicad_pcb
	(version 20260206)
	(generator "pcbnew")
	(generator_version "10.0")
	(general
		(thickness 1.6)
		(legacy_teardrops no)
	)
	(paper "A4")
	(title_block
		(title "fcb — 12433-1M.1206WZS1330.brd")
		(comment 1 "Open Vault / Knox (Wiwynn) / footprints 465-472 of 495")
	)
	(layers
		(0 "F.Cu" signal "TOP")
		(4 "In1.Cu" signal "L2GND")
		(6 "In2.Cu" signal "L3VCC")
		(2 "B.Cu" signal "BOTTOM")
		(9 "F.Adhes" user "F.Adhesive")
		(11 "B.Adhes" user "B.Adhesive")
		(13 "F.Paste" user "Package Geometry/Pastemask Top")
		(15 "B.Paste" user "Package Geometry/Pastemask Bottom")
		(5 "F.SilkS" user "Ref Des/Silkscreen Top")
		(7 "B.SilkS" user "Ref Des/Silkscreen Bottom")
		(1 "F.Mask" user "Board Geometry/Soldermask Top")
		(3 "B.Mask" user "Board Geometry/Soldermask Bottom")
		(17 "Dwgs.User" user "User.Drawings")
		(19 "Cmts.User" user "User.Comments")
		(21 "Eco1.User" user "User.Eco1")
		(23 "Eco2.User" user "User.Eco2")
		(25 "Edge.Cuts" user "Board Geometry/Outline")
		(27 "Margin" user)
		(31 "F.CrtYd" user "Package Geometry/Place Bound Top")
		(29 "B.CrtYd" user "Package Geometry/Place Bound Bottom")
		(35 "F.Fab" user "Ref Des/Assembly Top")
		(33 "B.Fab" user "Ref Des/Assembly Bottom")
	)
	(footprint ""
		(layer "F.Cu")
		(at 17.8816 -253.9492 90)
		(property "Reference" "R90"
			(at 0 0 90)
			(layer "F.SilkS")
			(hide yes)
			(effects
				(font
					(size 1.27 1.27)
				)
			)
		)
		(property "Value" "10KR2F-2-GP"
			(at 0.064008 -3.993896 90)
			(unlocked yes)
			(layer "F.Fab")
			(hide yes)
			(effects
				(font
					(size 1.016 1.016)
					(thickness 0.1524)
				)
			)
		)
		(property "Device Type" "R402H16"
			(at 0.064008 -5.517896 90)
			(unlocked yes)
			(layer "F.Fab")
			(hide yes)
			(effects
				(font
					(size 1.016 1.016)
					(thickness 0.1524)
				)
			)
		)
		(duplicate_pad_numbers_are_jumpers no)
		(fp_line
			(start 0.508 -0.9398)
			(end -0.508 -0.9398)
			(stroke
				(width 0.1524)
				(type default)
			)
			(layer "F.SilkS")
		)
		(fp_line
			(start -0.508 -0.9398)
			(end -0.508 0.9398)
			(stroke
				(width 0.1524)
				(type default)
			)
			(layer "F.SilkS")
		)
		(fp_rect
			(start -0.508 0.9398)
			(end 0.508 -0.9398)
			(stroke
				(width 0)
				(type default)
			)
			(fill no)
			(layer "F.CrtYd")
		)
		(fp_rect
			(start -0.508 0.9398)
			(end 0.508 -0.9398)
			(stroke
				(width 0)
				(type default)
			)
			(fill no)
			(layer "F.Fab")
		)
		(pad "1" smd custom
			(at 0 -0.4445 90)
			(size 0.1397 0.1397)
			(layers "F.Cu" "F.Mask" "F.Paste")
			(net "FANIN_5")
			(options
				(clearance outline)
				(anchor circle)
			)
			(primitives
				(gr_poly
					(pts
						(arc
							(start -0.1778 -0.2794)
							(mid -0.249642 -0.249642)
							(end -0.2794 -0.1778)
						)
						(arc
							(start -0.2794 0.1778)
							(mid -0.249642 0.249642)
							(end -0.1778 0.2794)
						)
						(arc
							(start 0.1778 0.2794)
							(mid 0.249642 0.249642)
							(end 0.2794 0.1778)
						)
						(arc
							(start 0.2794 -0.1778)
							(mid 0.249642 -0.249642)
							(end 0.1778 -0.2794)
						)
					)
					(width 0)
					(fill yes)
				)
			)
		)
		(pad "2" smd custom
			(at 0 0.4445 90)
			(size 0.1397 0.1397)
			(layers "F.Cu" "F.Mask" "F.Paste")
			(net "GND")
			(options
				(clearance outline)
				(anchor circle)
			)
			(primitives
				(gr_poly
					(pts
						(arc
							(start -0.1778 -0.2794)
							(mid -0.249642 -0.249642)
							(end -0.2794 -0.1778)
						)
						(arc
							(start -0.2794 0.1778)
							(mid -0.249642 0.249642)
							(end -0.1778 0.2794)
						)
						(arc
							(start 0.1778 0.2794)
							(mid 0.249642 0.249642)
							(end 0.2794 0.1778)
						)
						(arc
							(start 0.2794 -0.1778)
							(mid 0.249642 -0.249642)
							(end 0.1778 -0.2794)
						)
					)
					(width 0)
					(fill yes)
				)
			)
		)
	)
	(footprint ""
		(layer "F.Cu")
		(at 43.2054 -155.2956 180)
		(property "Reference" "C3"
			(at 0 0 180)
			(layer "F.SilkS")
			(hide yes)
			(effects
				(font
					(size 1.27 1.27)
				)
			)
		)
		(property "Value" "SC10U25V5KX-GP"
			(at -0.0762 -6.1214 180)
			(unlocked yes)
			(layer "F.Fab")
			(hide yes)
			(effects
				(font
					(size 1.016 1.016)
					(thickness 0.1524)
				)
			)
		)
		(property "Device Type" "C805H56"
			(at -0.0762 -8.1534 180)
			(unlocked yes)
			(layer "F.Fab")
			(hide yes)
			(effects
				(font
					(size 1.016 1.016)
					(thickness 0.1524)
				)
			)
		)
		(duplicate_pad_numbers_are_jumpers no)
		(fp_line
			(start 0.635 0)
			(end -0.635 0)
			(stroke
				(width 0.508)
				(type default)
			)
			(layer "F.SilkS")
		)
		(fp_rect
			(start -0.9652 1.778)
			(end 0.9652 -1.778)
			(stroke
				(width 0)
				(type default)
			)
			(fill no)
			(layer "F.CrtYd")
		)
		(fp_poly
			(pts
				(xy -0.9652 -1.778) (xy 0.9652 -1.778) (xy 0.9652 1.778) (xy -0.9652 1.778)
			)
			(stroke
				(width 0)
				(type default)
			)
			(fill no)
			(layer "F.Fab")
		)
		(pad "1" smd rect
			(at 0 -0.9652 180)
			(size 1.397 1.143)
			(layers "F.Cu" "F.Mask" "F.Paste")
			(net "NCT7904_3VSB")
		)
		(pad "2" smd rect
			(at 0 0.9652 180)
			(size 1.397 1.143)
			(layers "F.Cu" "F.Mask" "F.Paste")
			(net "GND")
		)
	)
	(footprint ""
		(layer "F.Cu")
		(at 22.733 -372.237 180)
		(property "Reference" "PC9"
			(at 0 0 180)
			(layer "F.SilkS")
			(hide yes)
			(effects
				(font
					(size 1.27 1.27)
				)
			)
		)
		(property "Value" "SC1U25V5KX-1GP"
			(at -0.0762 -6.1214 180)
			(unlocked yes)
			(layer "F.Fab")
			(hide yes)
			(effects
				(font
					(size 1.016 1.016)
					(thickness 0.1524)
				)
			)
		)
		(property "Device Type" "C805H58"
			(at -0.0762 -8.1534 180)
			(unlocked yes)
			(layer "F.Fab")
			(hide yes)
			(effects
				(font
					(size 1.016 1.016)
					(thickness 0.1524)
				)
			)
		)
		(duplicate_pad_numbers_are_jumpers no)
		(fp_line
			(start 0.635 0)
			(end -0.635 0)
			(stroke
				(width 0.508)
				(type default)
			)
			(layer "F.SilkS")
		)
		(fp_rect
			(start -0.9652 1.778)
			(end 0.9652 -1.778)
			(stroke
				(width 0)
				(type default)
			)
			(fill no)
			(layer "F.CrtYd")
		)
		(fp_poly
			(pts
				(xy -0.9652 -1.778) (xy 0.9652 -1.778) (xy 0.9652 1.778) (xy -0.9652 1.778)
			)
			(stroke
				(width 0)
				(type default)
			)
			(fill no)
			(layer "F.Fab")
		)
		(pad "1" smd rect
			(at 0 -0.9652 180)
			(size 1.397 1.143)
			(layers "F.Cu" "F.Mask" "F.Paste")
			(net "ADM1276_OV")
		)
		(pad "2" smd rect
			(at 0 0.9652 180)
			(size 1.397 1.143)
			(layers "F.Cu" "F.Mask" "F.Paste")
			(net "GND")
		)
	)
	(footprint ""
		(layer "F.Cu")
		(at 21.463 -91.9226 -90)
		(property "Reference" "D15"
			(at 0 0 270)
			(layer "F.SilkS")
			(hide yes)
			(effects
				(font
					(size 1.27 1.27)
				)
			)
		)
		(property "Value" "MBRS340T3G-GP"
			(at 0 -10.6172 270)
			(unlocked yes)
			(layer "F.Fab")
			(hide yes)
			(effects
				(font
					(size 1.016 1.016)
					(thickness 0.1524)
				)
			)
		)
		(property "Device Type" "D8059AKH101"
			(at 0 -12.1412 270)
			(unlocked yes)
			(layer "F.Fab")
			(hide yes)
			(effects
				(font
					(size 1.016 1.016)
					(thickness 0.1524)
				)
			)
		)
		(duplicate_pad_numbers_are_jumpers no)
		(fp_line
			(start 3.175 5.2832)
			(end -3.175 5.2832)
			(stroke
				(width 0.508)
				(type default)
			)
			(layer "F.SilkS")
		)
		(fp_line
			(start -3.175 5.1054)
			(end -3.175 -5.1054)
			(stroke
				(width 0.1524)
				(type default)
			)
			(layer "F.SilkS")
		)
		(fp_line
			(start 3.175 5.1054)
			(end -3.175 5.1054)
			(stroke
				(width 0.1524)
				(type default)
			)
			(layer "F.SilkS")
		)
		(fp_line
			(start -3.175 -5.1054)
			(end 3.175 -5.1054)
			(stroke
				(width 0.1524)
				(type default)
			)
			(layer "F.SilkS")
		)
		(fp_line
			(start 3.175 -5.1054)
			(end 3.175 5.1054)
			(stroke
				(width 0.1524)
				(type default)
			)
			(layer "F.SilkS")
		)
		(fp_rect
			(start -3.429 5.1816)
			(end 3.429 -5.1816)
			(stroke
				(width 0)
				(type default)
			)
			(fill no)
			(layer "F.CrtYd")
		)
		(fp_poly
			(pts
				(xy -3.429 -5.1816) (xy 3.429 -5.1816) (xy 3.429 5.1816) (xy -3.429 5.1816)
			)
			(stroke
				(width 0)
				(type default)
			)
			(fill no)
			(layer "F.Fab")
		)
		(pad "A" smd rect
			(at 0 -3.77571 270)
			(size 3.2512 2.159)
			(layers "F.Cu" "F.Mask" "F.Paste")
			(net "GND")
		)
		(pad "K" smd rect
			(at 0 3.77571 270)
			(size 3.2512 2.159)
			(layers "F.Cu" "F.Mask" "F.Paste")
			(net "P12VU")
		)
	)
	(footprint ""
		(layer "F.Cu")
		(at 35.8394 -357.097584 180)
		(property "Reference" "D19"
			(at 0 0 180)
			(layer "F.SilkS")
			(hide yes)
			(effects
				(font
					(size 1.27 1.27)
				)
			)
		)
		(property "Value" "CH751H-40PT-1GP"
			(at -0.1016 -4.4958 180)
			(unlocked yes)
			(layer "F.Fab")
			(hide yes)
			(effects
				(font
					(size 1.016 1.016)
					(thickness 0.1524)
				)
			)
		)
		(property "Device Type" "SOD80CAKH36"
			(at -0.1016 -6.0198 180)
			(unlocked yes)
			(layer "F.Fab")
			(hide yes)
			(effects
				(font
					(size 1.016 1.016)
					(thickness 0.1524)
				)
			)
		)
		(duplicate_pad_numbers_are_jumpers no)
		(fp_line
			(start 0.8128 1.8796)
			(end 0.8128 -1.8796)
			(stroke
				(width 0.1524)
				(type default)
			)
			(layer "F.SilkS")
		)
		(fp_line
			(start 0.8128 -1.8796)
			(end -0.8128 -1.8796)
			(stroke
				(width 0.1524)
				(type default)
			)
			(layer "F.SilkS")
		)
		(fp_line
			(start -0.6858 2.0066)
			(end 0.6858 2.0066)
			(stroke
				(width 0.4064)
				(type default)
			)
			(layer "F.SilkS")
		)
		(fp_line
			(start -0.8128 1.8796)
			(end 0.8128 1.8796)
			(stroke
				(width 0.1524)
				(type default)
			)
			(layer "F.SilkS")
		)
		(fp_line
			(start -0.8128 -1.8796)
			(end -0.8128 1.8796)
			(stroke
				(width 0.1524)
				(type default)
			)
			(layer "F.SilkS")
		)
		(fp_rect
			(start -0.889 2.2098)
			(end 0.889 -1.9558)
			(stroke
				(width 0)
				(type default)
			)
			(fill no)
			(layer "F.CrtYd")
		)
		(fp_rect
			(start -0.889 2.2098)
			(end 0.889 -1.9558)
			(stroke
				(width 0)
				(type default)
			)
			(fill no)
			(layer "F.Fab")
		)
		(pad "A" smd rect
			(at 0 -1.0668 180)
			(size 0.762 1.1684)
			(layers "F.Cu" "F.Mask" "F.Paste")
			(net "OTP_RETRY_C")
		)
		(pad "K" smd rect
			(at 0 1.0668 180)
			(size 0.762 1.1684)
			(layers "F.Cu" "F.Mask" "F.Paste")
			(net "OTP_RETRY_DIODE")
		)
	)
	(footprint ""
		(layer "F.Cu")
		(at 41.3766 -140.5382 -90)
		(property "Reference" "PC98"
			(at 0 0 270)
			(layer "F.SilkS")
			(hide yes)
			(effects
				(font
					(size 1.27 1.27)
				)
			)
		)
		(property "Value" "SCD1U50V3KX-GP"
			(at 0 -2.8194 270)
			(unlocked yes)
			(layer "F.Fab")
			(hide yes)
			(effects
				(font
					(size 1.016 1.016)
					(thickness 0.1524)
				)
			)
		)
		(property "Device Type" "C603H36"
			(at 0 -4.3434 270)
			(unlocked yes)
			(layer "F.Fab")
			(hide yes)
			(effects
				(font
					(size 1.016 1.016)
					(thickness 0.1524)
				)
			)
		)
		(duplicate_pad_numbers_are_jumpers no)
		(fp_line
			(start 0.508 0)
			(end -0.508 0)
			(stroke
				(width 0.2032)
				(type default)
			)
			(layer "F.SilkS")
		)
		(fp_rect
			(start -0.5842 1.3335)
			(end 0.5842 -1.3335)
			(stroke
				(width 0)
				(type default)
			)
			(fill no)
			(layer "F.CrtYd")
		)
		(fp_rect
			(start -0.5842 1.3335)
			(end 0.5842 -1.3335)
			(stroke
				(width 0)
				(type default)
			)
			(fill no)
			(layer "F.Fab")
		)
		(pad "1" smd custom
			(at 0 -0.762 270)
			(size 0.2159 0.2159)
			(layers "F.Cu" "F.Mask" "F.Paste")
			(net "P12VL_2490_EN_2")
			(options
				(clearance outline)
				(anchor circle)
			)
			(primitives
				(gr_poly
					(pts
						(arc
							(start -0.3302 -0.4318)
							(mid -0.402042 -0.402042)
							(end -0.4318 -0.3302)
						)
						(arc
							(start -0.4318 0.3302)
							(mid -0.402042 0.402042)
							(end -0.3302 0.4318)
						)
						(arc
							(start 0.3302 0.4318)
							(mid 0.402042 0.402042)
							(end 0.4318 0.3302)
						)
						(arc
							(start 0.4318 -0.3302)
							(mid 0.402042 -0.402042)
							(end 0.3302 -0.4318)
						)
					)
					(width 0)
					(fill yes)
				)
			)
		)
		(pad "2" smd custom
			(at 0 0.762 270)
			(size 0.2159 0.2159)
			(layers "F.Cu" "F.Mask" "F.Paste")
			(net "GND")
			(options
				(clearance outline)
				(anchor circle)
			)
			(primitives
				(gr_poly
					(pts
						(arc
							(start -0.3302 -0.4318)
							(mid -0.402042 -0.402042)
							(end -0.4318 -0.3302)
						)
						(arc
							(start -0.4318 0.3302)
							(mid -0.402042 0.402042)
							(end -0.3302 0.4318)
						)
						(arc
							(start 0.3302 0.4318)
							(mid 0.402042 0.402042)
							(end 0.4318 0.3302)
						)
						(arc
							(start 0.4318 -0.3302)
							(mid 0.402042 -0.402042)
							(end 0.3302 -0.4318)
						)
					)
					(width 0)
					(fill yes)
				)
			)
		)
	)
	(footprint ""
		(layer "F.Cu")
		(at 29.5402 -169.9006 180)
		(property "Reference" "R161"
			(at 0 0 180)
			(layer "F.SilkS")
			(hide yes)
			(effects
				(font
					(size 1.27 1.27)
				)
			)
		)
		(property "Value" "0R2J-2-GP"
			(at 0.064008 -3.993896 180)
			(unlocked yes)
			(layer "F.Fab")
			(hide yes)
			(effects
				(font
					(size 1.016 1.016)
					(thickness 0.1524)
				)
			)
		)
		(property "Device Type" "R402H16"
			(at 0.064008 -5.517896 180)
			(unlocked yes)
			(layer "F.Fab")
			(hide yes)
			(effects
				(font
					(size 1.016 1.016)
					(thickness 0.1524)
				)
			)
		)
		(duplicate_pad_numbers_are_jumpers no)
		(fp_line
			(start 0.508 -0.9398)
			(end -0.508 -0.9398)
			(stroke
				(width 0.1524)
				(type default)
			)
			(layer "F.SilkS")
		)
		(fp_line
			(start -0.508 -0.9398)
			(end -0.508 0.9398)
			(stroke
				(width 0.1524)
				(type default)
			)
			(layer "F.SilkS")
		)
		(fp_rect
			(start -0.508 0.9398)
			(end 0.508 -0.9398)
			(stroke
				(width 0)
				(type default)
			)
			(fill no)
			(layer "F.CrtYd")
		)
		(fp_rect
			(start -0.508 0.9398)
			(end 0.508 -0.9398)
			(stroke
				(width 0)
				(type default)
			)
			(fill no)
			(layer "F.Fab")
		)
		(pad "1" smd custom
			(at 0 -0.4445 180)
			(size 0.1397 0.1397)
			(layers "F.Cu" "F.Mask" "F.Paste")
			(net "NCT7904D_PWM1")
			(options
				(clearance outline)
				(anchor circle)
			)
			(primitives
				(gr_poly
					(pts
						(arc
							(start -0.1778 -0.2794)
							(mid -0.249642 -0.249642)
							(end -0.2794 -0.1778)
						)
						(arc
							(start -0.2794 0.1778)
							(mid -0.249642 0.249642)
							(end -0.1778 0.2794)
						)
						(arc
							(start 0.1778 0.2794)
							(mid 0.249642 0.249642)
							(end 0.2794 0.1778)
						)
						(arc
							(start 0.2794 -0.1778)
							(mid 0.249642 -0.249642)
							(end 0.1778 -0.2794)
						)
					)
					(width 0)
					(fill yes)
				)
			)
		)
		(pad "2" smd custom
			(at 0 0.4445 180)
			(size 0.1397 0.1397)
			(layers "F.Cu" "F.Mask" "F.Paste")
			(net "PWM_BUFFER_IN_FAN1_FAN2")
			(options
				(clearance outline)
				(anchor circle)
			)
			(primitives
				(gr_poly
					(pts
						(arc
							(start -0.1778 -0.2794)
							(mid -0.249642 -0.249642)
							(end -0.2794 -0.1778)
						)
						(arc
							(start -0.2794 0.1778)
							(mid -0.249642 0.249642)
							(end -0.1778 0.2794)
						)
						(arc
							(start 0.1778 0.2794)
							(mid 0.249642 0.249642)
							(end 0.2794 0.1778)
						)
						(arc
							(start 0.2794 -0.1778)
							(mid 0.249642 -0.249642)
							(end 0.1778 -0.2794)
						)
					)
					(width 0)
					(fill yes)
				)
			)
		)
	)
	(footprint ""
		(layer "F.Cu")
		(at 8.3566 -422.275)
		(property "Reference" "R119"
			(at 0 0 0)
			(layer "F.SilkS")
			(hide yes)
			(effects
				(font
					(size 1.27 1.27)
				)
			)
		)
		(property "Value" "2KR2F-3-GP"
			(at 0.064008 -3.993896 0)
			(unlocked yes)
			(layer "F.Fab")
			(hide yes)
			(effects
				(font
					(size 1.016 1.016)
					(thickness 0.1524)
				)
			)
		)
		(property "Device Type" "R402H16"
			(at 0.064008 -5.517896 0)
			(unlocked yes)
			(layer "F.Fab")
			(hide yes)
			(effects
				(font
					(size 1.016 1.016)
					(thickness 0.1524)
				)
			)
		)
		(duplicate_pad_numbers_are_jumpers no)
		(fp_line
			(start -0.508 -0.9398)
			(end -0.508 0.9398)
			(stroke
				(width 0.1524)
				(type default)
			)
			(layer "F.SilkS")
		)
		(fp_line
			(start 0.508 -0.9398)
			(end -0.508 -0.9398)
			(stroke
				(width 0.1524)
				(type default)
			)
			(layer "F.SilkS")
		)
		(fp_rect
			(start -0.508 0.9398)
			(end 0.508 -0.9398)
			(stroke
				(width 0)
				(type default)
			)
			(fill no)
			(layer "F.CrtYd")
		)
		(fp_rect
			(start -0.508 0.9398)
			(end 0.508 -0.9398)
			(stroke
				(width 0)
				(type default)
			)
			(fill no)
			(layer "F.Fab")
		)
		(pad "1" smd custom
			(at 0 -0.4445)
			(size 0.1397 0.1397)
			(layers "F.Cu" "F.Mask" "F.Paste")
			(net "LED_DR_LED1")
			(options
				(clearance outline)
				(anchor circle)
			)
			(primitives
				(gr_poly
					(pts
						(arc
							(start -0.1778 -0.2794)
							(mid -0.249642 -0.249642)
							(end -0.2794 -0.1778)
						)
						(arc
							(start -0.2794 0.1778)
							(mid -0.249642 0.249642)
							(end -0.1778 0.2794)
						)
						(arc
							(start 0.1778 0.2794)
							(mid 0.249642 0.249642)
							(end 0.2794 0.1778)
						)
						(arc
							(start 0.2794 -0.1778)
							(mid 0.249642 -0.249642)
							(end 0.1778 -0.2794)
						)
					)
					(width 0)
					(fill yes)
				)
			)
		)
		(pad "2" smd custom
			(at 0 0.4445)
			(size 0.1397 0.1397)
			(layers "F.Cu" "F.Mask" "F.Paste")
			(net "LED_DR_LED1_B")
			(options
				(clearance outline)
				(anchor circle)
			)
			(primitives
				(gr_poly
					(pts
						(arc
							(start -0.1778 -0.2794)
							(mid -0.249642 -0.249642)
							(end -0.2794 -0.1778)
						)
						(arc
							(start -0.2794 0.1778)
							(mid -0.249642 0.249642)
							(end -0.1778 0.2794)
						)
						(arc
							(start 0.1778 0.2794)
							(mid 0.249642 0.249642)
							(end 0.2794 0.1778)
						)
						(arc
							(start 0.2794 -0.1778)
							(mid 0.249642 -0.249642)
							(end 0.1778 -0.2794)
						)
					)
					(width 0)
					(fill yes)
				)
			)
		)
	)
)
